#ISCELL
  cls sheet_a1 *
  *
#CELL
  pld xc7a200t_2fbg484c_fbg484 *
  page163_i1
#ISCELL
  cls offpage_bi *
  page163_i112
#ISCELL
  cls offpage_bi *
  page163_i113
#ISCELL
  cls offpage_bi *
  page163_i114
#ISCELL
  cls offpage_bi *
  page163_i115
#CELL
  passive resistor *
  page163_i120
#ISCELL
  cls gnd_sg *
  page163_i124
#ISCELL
  cls vcc *
  page163_i125
#CELL
  passive resistor *
  page163_i126
#CELL
  passive resistor *
  page163_i127
#CELL
  passive resistor *
  page163_i128
#ISCELL
  cls vcc *
  page163_i130
#ISCELL
  cls gnd_sg *
  page163_i131
#CELL
  passive resistor *
  page163_i132
#CELL
  passive resistor *
  page163_i133
#CELL
  passive resistor *
  page163_i134
#CELL
  passive resistor *
  page163_i135
#ISCELL
  cls offpage_bi *
  page163_i14
#ISCELL
  cls offpage_bi *
  page163_i15
#ISCELL
  cls offpage_bi *
  page163_i16
#ISCELL
  cls offpage_bi *
  page163_i17
#ISCELL
  cls offpage_bi *
  page163_i18
#ISCELL
  cls offpage_bi *
  page163_i19
#ISCELL
  cls offpage_in *
  page163_i30
#ISCELL
  cls offpage_in *
  page163_i31
#ISCELL
  cls offpage_out *
  page163_i32
#ISCELL
  cls offpage_out *
  page163_i33
#ISCELL
  cls offpage_out *
  page163_i34
#ISCELL
  cls offpage_out *
  page163_i35
#CELL
  passive resistor *
  page163_i36
#CELL
  passive resistor *
  page163_i37
#CELL
  passive resistor *
  page163_i38
#CELL
  passive resistor *
  page163_i39
#ISCELL
  cls offpage_in *
  page163_i4
#ISCELL
  cls offpage_bi *
  page163_i40
#ISCELL
  cls offpage_bi *
  page163_i41
#ISCELL
  cls offpage_bi *
  page163_i42
#ISCELL
  cls offpage_bi *
  page163_i43
#ISCELL
  cls offpage_bi *
  page163_i44
#ISCELL
  cls offpage_bi *
  page163_i45
#ISCELL
  cls offpage_bi *
  page163_i46
#ISCELL
  cls offpage_bi *
  page163_i47
#ISCELL
  cls offpage_bi *
  page163_i48
#ISCELL
  cls offpage_bi *
  page163_i49
#ISCELL
  cls offpage_in *
  page163_i5
